# S9S_MB_2U (Grand Teton) — schematic netlist excerpt (pin names and nets, part order shuffled) for the footprints in the layout excerpt that follows; sources: Cadence DE-HDL packaged netlist, KiCad conversion of 03242023_DA0F0TMBIJ0_F0T_Motherboard_J_brd_V01_OCP.brd

C495  Q_CAP  47UF 4V 20% X6S  pkg C0805  page 75 : A = PVCCD_HV_CPU0 ; B = GND
R577  Q_RES  33.2 1% CHIP  pkg 0402LF  page 241 : A = SMB_HOST_3V3AUX_SCL_R4 ; B = SMB_HOST_3V3AUX_SCL_R
PC326  Q_CAPP  330UF 2.5V +10/-35% EMPTY  pkg SMLF  page 267 : A = PVCCIN_CPU0 ; B = GND

(kicad_pcb
	(version 20260206)
	(generator "pcbnew")
	(generator_version "10.0")
	(general
		(thickness 1.6)
		(legacy_teardrops no)
	)
	(paper "A4")
	(title_block
		(title "03242023_DA0F0TMBIJ0_F0T_Motherboard_J_brd_V01_OCP.brd")
		(comment 1 "Grand Teton / footprints 5680-5682 of 6105")
	)
	(layers
		(0 "F.Cu" signal "TOP")
		(4 "In1.Cu" signal "GND")
		(6 "In2.Cu" signal "IN1")
		(8 "In3.Cu" signal "GND1")
		(10 "In4.Cu" signal "IN2")
		(12 "In5.Cu" signal "GND2")
		(14 "In6.Cu" signal "IN3")
		(16 "In7.Cu" signal "GND3")
		(18 "In8.Cu" signal "VCC")
		(20 "In9.Cu" signal "VCC1")
		(22 "In10.Cu" signal "GND4")
		(24 "In11.Cu" signal "IN4")
		(26 "In12.Cu" signal "GND5")
		(28 "In13.Cu" signal "IN5")
		(30 "In14.Cu" signal "GND6")
		(32 "In15.Cu" signal "IN6")
		(34 "In16.Cu" signal "GND7")
		(2 "B.Cu" signal "BOTTOM")
		(9 "F.Adhes" user "F.Adhesive")
		(11 "B.Adhes" user "B.Adhesive")
		(13 "F.Paste" user "Package Geometry/Pastemask Top")
		(15 "B.Paste" user "Package Geometry/Pastemask Bottom")
		(5 "F.SilkS" user "Ref Des/Silkscreen Top")
		(7 "B.SilkS" user "Ref Des/Silkscreen Bottom")
		(1 "F.Mask" user "Board Geometry/Soldermask Top")
		(3 "B.Mask" user "Board Geometry/Soldermask Bottom")
		(17 "Dwgs.User" user "User.Drawings")
		(19 "Cmts.User" user "User.Comments")
		(21 "Eco1.User" user "User.Eco1")
		(23 "Eco2.User" user "User.Eco2")
		(25 "Edge.Cuts" user "Board Geometry/Outline")
		(27 "Margin" user)
		(31 "F.CrtYd" user "Package Geometry/Place Bound Top")
		(29 "B.CrtYd" user "Package Geometry/Place Bound Bottom")
		(35 "F.Fab" user "Ref Des/Assembly Top")
		(33 "B.Fab" user "Ref Des/Assembly Bottom")
	)
	(footprint ""
		(layer "B.Cu")
		(at 352.430334 -326.867012 -90)
		(property "Reference" "PC326"
			(at 0 0 90)
			(layer "B.SilkS")
			(hide yes)
			(effects
				(font
					(size 1.27 1.27)
				)
				(justify mirror)
			)
		)
		(property "Value" ""
			(at 0 0 90)
			(layer "B.Fab")
			(effects
				(font
					(size 1.27 1.27)
				)
				(justify mirror)
			)
		)
		(duplicate_pad_numbers_are_jumpers no)
		(fp_line
			(start -4.533392 2.249932)
			(end 4.533392 2.249932)
			(stroke
				(width 0.1524)
				(type default)
			)
			(layer "B.SilkS")
		)
		(fp_line
			(start 4.533392 2.249932)
			(end 4.533392 -2.249932)
			(stroke
				(width 0.1524)
				(type default)
			)
			(layer "B.SilkS")
		)
		(fp_line
			(start -4.533392 -2.249932)
			(end -4.533392 2.249932)
			(stroke
				(width 0.1524)
				(type default)
			)
			(layer "B.SilkS")
		)
		(fp_line
			(start 4.533392 -2.249932)
			(end -4.533392 -2.249932)
			(stroke
				(width 0.1524)
				(type default)
			)
			(layer "B.SilkS")
		)
		(fp_rect
			(start 5.39242 2.326132)
			(end 4.533392 -2.326132)
			(stroke
				(width 0)
				(type default)
			)
			(fill yes)
			(layer "B.SilkS")
		)
		(fp_line
			(start -3.750056 2.249932)
			(end 3.750056 2.249932)
			(stroke
				(width 0.1)
				(type default)
			)
			(layer "B.Fab")
		)
		(fp_line
			(start 3.750056 2.249932)
			(end 3.750056 -2.249932)
			(stroke
				(width 0.1)
				(type default)
			)
			(layer "B.Fab")
		)
		(fp_line
			(start -3.750056 -2.249932)
			(end -3.750056 2.249932)
			(stroke
				(width 0.1)
				(type default)
			)
			(layer "B.Fab")
		)
		(fp_line
			(start 3.750056 -2.249932)
			(end -3.750056 -2.249932)
			(stroke
				(width 0.1)
				(type default)
			)
			(layer "B.Fab")
		)
		(fp_text user "-"
			(at -4.702556 1.251204 270)
			(unlocked yes)
			(layer "B.SilkS")
			(effects
				(font
					(size 1.905 1.4224)
					(thickness 0.1524)
				)
				(justify left mirror)
			)
		)
		(fp_text user "+"
			(at 6.322314 0.786384 180)
			(unlocked yes)
			(layer "B.SilkS")
			(effects
				(font
					(size 1.905 1.4224)
					(thickness 0.1524)
				)
				(justify left mirror)
			)
		)
		(fp_text user "+"
			(at 6.322314 0.786384 180)
			(unlocked yes)
			(layer "B.Fab")
			(effects
				(font
					(size 1.905 1.4224)
					(thickness 0.1524)
				)
				(justify left mirror)
			)
		)
		(fp_text user "-"
			(at -4.8514 -0.14605 270)
			(unlocked yes)
			(layer "B.Fab")
			(effects
				(font
					(size 1.905 1.4224)
					(thickness 0.1524)
				)
				(justify left mirror)
			)
		)
		(pad "1" smd rect
			(at 3.199892 0 90)
			(size 2.413 2.8194)
			(layers "B.Cu" "B.Mask" "B.Paste")
			(net "PVCCIN_CPU0")
		)
		(pad "2" smd rect
			(at -3.199892 0 90)
			(size 2.413 2.8194)
			(layers "B.Cu" "B.Mask" "B.Paste")
			(net "GND")
		)
	)
	(footprint ""
		(layer "B.Cu")
		(at 237.40618 -132.422392)
		(property "Reference" "R577"
			(at 0 0 0)
			(layer "B.SilkS")
			(hide yes)
			(effects
				(font
					(size 1.27 1.27)
				)
				(justify mirror)
			)
		)
		(property "Value" ""
			(at 0 0 0)
			(layer "B.Fab")
			(effects
				(font
					(size 1.27 1.27)
				)
				(justify mirror)
			)
		)
		(duplicate_pad_numbers_are_jumpers no)
		(fp_line
			(start -0.7874 -0.4064)
			(end -0.7874 0.4064)
			(stroke
				(width 0.1524)
				(type default)
			)
			(layer "B.SilkS")
		)
		(fp_line
			(start -0.7874 0.4064)
			(end 0.7874 0.4064)
			(stroke
				(width 0.1524)
				(type default)
			)
			(layer "B.SilkS")
		)
		(fp_line
			(start 0.7874 -0.4064)
			(end -0.7874 -0.4064)
			(stroke
				(width 0.1524)
				(type default)
			)
			(layer "B.SilkS")
		)
		(fp_line
			(start 0.7874 0.4064)
			(end 0.7874 -0.4064)
			(stroke
				(width 0.1524)
				(type default)
			)
			(layer "B.SilkS")
		)
		(fp_line
			(start -0.67945 -0.3048)
			(end -0.67945 0.3048)
			(stroke
				(width 0.1)
				(type default)
			)
			(layer "B.Fab")
		)
		(fp_line
			(start -0.67945 0.3048)
			(end -0.120396 0.3048)
			(stroke
				(width 0.1)
				(type default)
			)
			(layer "B.Fab")
		)
		(fp_line
			(start -0.12065 -0.3048)
			(end -0.67945 -0.3048)
			(stroke
				(width 0.1)
				(type default)
			)
			(layer "B.Fab")
		)
		(fp_line
			(start -0.12065 -0.2794)
			(end -0.12065 -0.3048)
			(stroke
				(width 0.1)
				(type default)
			)
			(layer "B.Fab")
		)
		(fp_line
			(start -0.120396 0.2794)
			(end 0.12065 0.2794)
			(stroke
				(width 0.1)
				(type default)
			)
			(layer "B.Fab")
		)
		(fp_line
			(start -0.120396 0.3048)
			(end -0.120396 0.2794)
			(stroke
				(width 0.1)
				(type default)
			)
			(layer "B.Fab")
		)
		(fp_line
			(start 0.12065 -0.305054)
			(end 0.12065 -0.2794)
			(stroke
				(width 0.1)
				(type default)
			)
			(layer "B.Fab")
		)
		(fp_line
			(start 0.12065 -0.2794)
			(end -0.12065 -0.2794)
			(stroke
				(width 0.1)
				(type default)
			)
			(layer "B.Fab")
		)
		(fp_line
			(start 0.12065 0.2794)
			(end 0.12065 0.3048)
			(stroke
				(width 0.1)
				(type default)
			)
			(layer "B.Fab")
		)
		(fp_line
			(start 0.12065 0.3048)
			(end 0.67945 0.3048)
			(stroke
				(width 0.1)
				(type default)
			)
			(layer "B.Fab")
		)
		(fp_line
			(start 0.67945 -0.305054)
			(end 0.12065 -0.305054)
			(stroke
				(width 0.1)
				(type default)
			)
			(layer "B.Fab")
		)
		(fp_line
			(start 0.67945 0.3048)
			(end 0.67945 -0.305054)
			(stroke
				(width 0.1)
				(type default)
			)
			(layer "B.Fab")
		)
		(pad "1" smd circle
			(at 0.40005 0 180)
			(size 0 0)
			(layers "B.Cu" "B.Mask" "B.Paste")
			(net "SMB_HOST_3V3AUX_SCL_R4")
		)
		(pad "2" smd circle
			(at -0.40005 0 180)
			(size 0 0)
			(layers "B.Cu" "B.Mask" "B.Paste")
			(net "SMB_HOST_3V3AUX_SCL_R")
		)
	)
	(footprint ""
		(layer "B.Cu")
		(at 351.841308 -248.498106 -90)
		(property "Reference" "C495"
			(at 0 0 90)
			(layer "B.SilkS")
			(hide yes)
			(effects
				(font
					(size 1.27 1.27)
				)
				(justify mirror)
			)
		)
		(property "Value" ""
			(at 0 0 90)
			(layer "B.Fab")
			(effects
				(font
					(size 1.27 1.27)
				)
				(justify mirror)
			)
		)
		(duplicate_pad_numbers_are_jumpers no)
		(fp_line
			(start -1.524 0.762)
			(end 1.524 0.762)
			(stroke
				(width 0.1524)
				(type default)
			)
			(layer "B.SilkS")
		)
		(fp_line
			(start 1.524 0.762)
			(end 1.524 -0.762)
			(stroke
				(width 0.1524)
				(type default)
			)
			(layer "B.SilkS")
		)
		(fp_line
			(start -1.524 -0.762)
			(end -1.524 0.762)
			(stroke
				(width 0.1524)
				(type default)
			)
			(layer "B.SilkS")
		)
		(fp_line
			(start 1.524 -0.762)
			(end -1.524 -0.762)
			(stroke
				(width 0.1524)
				(type default)
			)
			(layer "B.SilkS")
		)
		(fp_line
			(start -1.1049 0.724916)
			(end -1.1049 -0.724916)
			(stroke
				(width 0.1)
				(type default)
			)
			(layer "B.Fab")
		)
		(fp_line
			(start 1.1049 0.724916)
			(end -1.1049 0.724916)
			(stroke
				(width 0.1)
				(type default)
			)
			(layer "B.Fab")
		)
		(fp_line
			(start -1.1049 -0.724916)
			(end 1.1049 -0.724916)
			(stroke
				(width 0.1)
				(type default)
			)
			(layer "B.Fab")
		)
		(fp_line
			(start 1.1049 -0.724916)
			(end 1.1049 0.724916)
			(stroke
				(width 0.1)
				(type default)
			)
			(layer "B.Fab")
		)
		(pad "1" smd rect
			(at 0.889 0 270)
			(size 1.016 1.27)
			(layers "B.Cu" "B.Mask" "B.Paste")
			(net "PVCCD_HV_CPU0")
		)
		(pad "2" smd rect
			(at -0.889 0 270)
			(size 1.016 1.27)
			(layers "B.Cu" "B.Mask" "B.Paste")
			(net "GND")
		)
	)
)
